(kicad_pcb
	(version 20260206)
	(generator "pcbnew")
	(generator_version "10.0")
	(general
		(thickness 1.6)
		(legacy_teardrops no)
	)
	(paper "A4")
	(title_block
		(title "03242023_DA0F0TMBIJ0_F0T_Motherboard_J_brd_V01_OCP.brd")
		(comment 1 "Grand Teton / footprints 5885-5890 of 6105")
	)
	(layers
		(0 "F.Cu" signal "TOP")
		(4 "In1.Cu" signal "GND")
		(6 "In2.Cu" signal "IN1")
		(8 "In3.Cu" signal "GND1")
		(10 "In4.Cu" signal "IN2")
		(12 "In5.Cu" signal "GND2")
		(14 "In6.Cu" signal "IN3")
		(16 "In7.Cu" signal "GND3")
		(18 "In8.Cu" signal "VCC")
		(20 "In9.Cu" signal "VCC1")
		(22 "In10.Cu" signal "GND4")
		(24 "In11.Cu" signal "IN4")
		(26 "In12.Cu" signal "GND5")
		(28 "In13.Cu" signal "IN5")
		(30 "In14.Cu" signal "GND6")
		(32 "In15.Cu" signal "IN6")
		(34 "In16.Cu" signal "GND7")
		(2 "B.Cu" signal "BOTTOM")
		(9 "F.Adhes" user "F.Adhesive")
		(11 "B.Adhes" user "B.Adhesive")
		(13 "F.Paste" user "Package Geometry/Pastemask Top")
		(15 "B.Paste" user "Package Geometry/Pastemask Bottom")
		(5 "F.SilkS" user "Ref Des/Silkscreen Top")
		(7 "B.SilkS" user "Ref Des/Silkscreen Bottom")
		(1 "F.Mask" user "Board Geometry/Soldermask Top")
		(3 "B.Mask" user "Board Geometry/Soldermask Bottom")
		(17 "Dwgs.User" user "User.Drawings")
		(19 "Cmts.User" user "User.Comments")
		(21 "Eco1.User" user "User.Eco1")
		(23 "Eco2.User" user "User.Eco2")
		(25 "Edge.Cuts" user "Board Geometry/Outline")
		(27 "Margin" user)
		(31 "F.CrtYd" user "Package Geometry/Place Bound Top")
		(29 "B.CrtYd" user "Package Geometry/Place Bound Bottom")
		(35 "F.Fab" user "Ref Des/Assembly Top")
		(33 "B.Fab" user "Ref Des/Assembly Bottom")
	)
	(footprint ""
		(layer "B.Cu")
		(at 233.2482 -423.0116 90)
		(property "Reference" "C2371"
			(at 0 0 90)
			(layer "B.SilkS")
			(hide yes)
			(effects
				(font
					(size 1.27 1.27)
				)
				(justify mirror)
			)
		)
		(property "Value" ""
			(at 0 0 90)
			(layer "B.Fab")
			(effects
				(font
					(size 1.27 1.27)
				)
				(justify mirror)
			)
		)
		(duplicate_pad_numbers_are_jumpers no)
		(fp_line
			(start 0.7874 -0.4064)
			(end -0.7874 -0.4064)
			(stroke
				(width 0.1524)
				(type default)
			)
			(layer "B.SilkS")
		)
		(fp_line
			(start -0.7874 -0.4064)
			(end -0.7874 0.4064)
			(stroke
				(width 0.1524)
				(type default)
			)
			(layer "B.SilkS")
		)
		(fp_line
			(start 0.7874 0.4064)
			(end 0.7874 -0.4064)
			(stroke
				(width 0.1524)
				(type default)
			)
			(layer "B.SilkS")
		)
		(fp_line
			(start -0.7874 0.4064)
			(end 0.7874 0.4064)
			(stroke
				(width 0.1524)
				(type default)
			)
			(layer "B.SilkS")
		)
		(fp_line
			(start 0.67945 -0.305054)
			(end 0.12065 -0.305054)
			(stroke
				(width 0.1)
				(type default)
			)
			(layer "B.Fab")
		)
		(fp_line
			(start 0.12065 -0.305054)
			(end 0.12065 -0.2794)
			(stroke
				(width 0.1)
				(type default)
			)
			(layer "B.Fab")
		)
		(fp_line
			(start -0.12065 -0.3048)
			(end -0.67945 -0.3048)
			(stroke
				(width 0.1)
				(type default)
			)
			(layer "B.Fab")
		)
		(fp_line
			(start -0.67945 -0.3048)
			(end -0.67945 0.3048)
			(stroke
				(width 0.1)
				(type default)
			)
			(layer "B.Fab")
		)
		(fp_line
			(start 0.12065 -0.2794)
			(end -0.12065 -0.2794)
			(stroke
				(width 0.1)
				(type default)
			)
			(layer "B.Fab")
		)
		(fp_line
			(start -0.12065 -0.2794)
			(end -0.12065 -0.3048)
			(stroke
				(width 0.1)
				(type default)
			)
			(layer "B.Fab")
		)
		(fp_line
			(start 0.12065 0.2794)
			(end 0.12065 0.3048)
			(stroke
				(width 0.1)
				(type default)
			)
			(layer "B.Fab")
		)
		(fp_line
			(start -0.120396 0.2794)
			(end 0.12065 0.2794)
			(stroke
				(width 0.1)
				(type default)
			)
			(layer "B.Fab")
		)
		(fp_line
			(start 0.67945 0.3048)
			(end 0.67945 -0.305054)
			(stroke
				(width 0.1)
				(type default)
			)
			(layer "B.Fab")
		)
		(fp_line
			(start 0.12065 0.3048)
			(end 0.67945 0.3048)
			(stroke
				(width 0.1)
				(type default)
			)
			(layer "B.Fab")
		)
		(fp_line
			(start -0.120396 0.3048)
			(end -0.120396 0.2794)
			(stroke
				(width 0.1)
				(type default)
			)
			(layer "B.Fab")
		)
		(fp_line
			(start -0.67945 0.3048)
			(end -0.120396 0.3048)
			(stroke
				(width 0.1)
				(type default)
			)
			(layer "B.Fab")
		)
		(pad "1" smd circle
			(at 0.40005 0 270)
			(size 0 0)
			(layers "B.Cu" "B.Mask" "B.Paste")
			(net "FM_AC_PWR_BTN_PDB_N")
		)
		(pad "2" smd circle
			(at -0.40005 0 270)
			(size 0 0)
			(layers "B.Cu" "B.Mask" "B.Paste")
			(net "GND")
		)
	)
	(footprint ""
		(layer "B.Cu")
		(at 375.943876 -366.755426 90)
		(property "Reference" "PC1255"
			(at 0 0 90)
			(layer "B.SilkS")
			(hide yes)
			(effects
				(font
					(size 1.27 1.27)
				)
				(justify mirror)
			)
		)
		(property "Value" ""
			(at 0 0 90)
			(layer "B.Fab")
			(effects
				(font
					(size 1.27 1.27)
				)
				(justify mirror)
			)
		)
		(duplicate_pad_numbers_are_jumpers no)
		(fp_line
			(start 1.524 -0.762)
			(end -1.524 -0.762)
			(stroke
				(width 0.1524)
				(type default)
			)
			(layer "B.SilkS")
		)
		(fp_line
			(start -1.524 -0.762)
			(end -1.524 0.762)
			(stroke
				(width 0.1524)
				(type default)
			)
			(layer "B.SilkS")
		)
		(fp_line
			(start 1.524 0.762)
			(end 1.524 -0.762)
			(stroke
				(width 0.1524)
				(type default)
			)
			(layer "B.SilkS")
		)
		(fp_line
			(start -1.524 0.762)
			(end 1.524 0.762)
			(stroke
				(width 0.1524)
				(type default)
			)
			(layer "B.SilkS")
		)
		(fp_line
			(start 1.1049 -0.724916)
			(end 1.1049 0.724916)
			(stroke
				(width 0.1)
				(type default)
			)
			(layer "B.Fab")
		)
		(fp_line
			(start -1.1049 -0.724916)
			(end 1.1049 -0.724916)
			(stroke
				(width 0.1)
				(type default)
			)
			(layer "B.Fab")
		)
		(fp_line
			(start 1.1049 0.724916)
			(end -1.1049 0.724916)
			(stroke
				(width 0.1)
				(type default)
			)
			(layer "B.Fab")
		)
		(fp_line
			(start -1.1049 0.724916)
			(end -1.1049 -0.724916)
			(stroke
				(width 0.1)
				(type default)
			)
			(layer "B.Fab")
		)
		(pad "1" smd rect
			(at 0.889 0 90)
			(size 1.016 1.27)
			(layers "B.Cu" "B.Mask" "B.Paste")
			(net "PVPP_HBM_CPU0")
		)
		(pad "2" smd rect
			(at -0.889 0 90)
			(size 1.016 1.27)
			(layers "B.Cu" "B.Mask" "B.Paste")
			(net "GND")
		)
	)
	(footprint ""
		(layer "B.Cu")
		(at 286.275526 -315.46673 -90)
		(property "Reference" "D43"
			(at 1.767332 3.355086 0)
			(unlocked yes)
			(layer "B.SilkS")
			(effects
				(font
					(size 0.7874 0.5842)
					(thickness 0.1524)
				)
				(justify left mirror)
			)
		)
		(property "Value" ""
			(at 0 0 90)
			(layer "B.Fab")
			(effects
				(font
					(size 1.27 1.27)
				)
				(justify mirror)
			)
		)
		(duplicate_pad_numbers_are_jumpers no)
		(fp_line
			(start -2.050796 0.700024)
			(end 2.050796 0.700024)
			(stroke
				(width 0.1524)
				(type default)
			)
			(layer "B.SilkS")
		)
		(fp_line
			(start 2.050796 0.700024)
			(end 2.050796 -0.700024)
			(stroke
				(width 0.1524)
				(type default)
			)
			(layer "B.SilkS")
		)
		(fp_line
			(start -2.343404 0.6985)
			(end -2.216404 0.6985)
			(stroke
				(width 0.1524)
				(type default)
			)
			(layer "B.SilkS")
		)
		(fp_line
			(start -2.229104 0.6985)
			(end -2.051304 0.6985)
			(stroke
				(width 0.1524)
				(type default)
			)
			(layer "B.SilkS")
		)
		(fp_line
			(start -2.051304 0.6985)
			(end -2.051304 0.635)
			(stroke
				(width 0.1524)
				(type default)
			)
			(layer "B.SilkS")
		)
		(fp_line
			(start -2.152904 0.635)
			(end -2.152904 -0.6985)
			(stroke
				(width 0.1524)
				(type default)
			)
			(layer "B.SilkS")
		)
		(fp_line
			(start -2.051304 0.635)
			(end -2.152904 0.635)
			(stroke
				(width 0.1524)
				(type default)
			)
			(layer "B.SilkS")
		)
		(fp_line
			(start 0.30607 0.500126)
			(end -0.193802 0)
			(stroke
				(width 0.1524)
				(type default)
			)
			(layer "B.SilkS")
		)
		(fp_line
			(start -0.193802 0)
			(end 0.30607 -0.500126)
			(stroke
				(width 0.1524)
				(type default)
			)
			(layer "B.SilkS")
		)
		(fp_line
			(start -0.293878 -0.500126)
			(end -0.293878 0.500126)
			(stroke
				(width 0.1524)
				(type default)
			)
			(layer "B.SilkS")
		)
		(fp_line
			(start 0.30607 -0.500126)
			(end 0.30607 0.500126)
			(stroke
				(width 0.1524)
				(type default)
			)
			(layer "B.SilkS")
		)
		(fp_line
			(start -2.064004 -0.6731)
			(end -2.064004 -0.6985)
			(stroke
				(width 0.1524)
				(type default)
			)
			(layer "B.SilkS")
		)
		(fp_line
			(start -2.343404 -0.6985)
			(end -2.343404 0.6985)
			(stroke
				(width 0.1524)
				(type default)
			)
			(layer "B.SilkS")
		)
		(fp_line
			(start -2.229104 -0.6985)
			(end -2.229104 0.6985)
			(stroke
				(width 0.1524)
				(type default)
			)
			(layer "B.SilkS")
		)
		(fp_line
			(start -2.152904 -0.6985)
			(end -2.343404 -0.6985)
			(stroke
				(width 0.1524)
				(type default)
			)
			(layer "B.SilkS")
		)
		(fp_line
			(start -2.064004 -0.6985)
			(end -2.229104 -0.6985)
			(stroke
				(width 0.1524)
				(type default)
			)
			(layer "B.SilkS")
		)
		(fp_line
			(start -2.050796 -0.700024)
			(end -2.050796 0.700024)
			(stroke
				(width 0.1524)
				(type default)
			)
			(layer "B.SilkS")
		)
		(fp_line
			(start 2.050796 -0.700024)
			(end -2.050796 -0.700024)
			(stroke
				(width 0.1524)
				(type default)
			)
			(layer "B.SilkS")
		)
		(fp_line
			(start -0.899922 0.700024)
			(end 0.899922 0.700024)
			(stroke
				(width 0.1)
				(type default)
			)
			(layer "B.Fab")
		)
		(fp_line
			(start 0.899922 0.700024)
			(end 0.899922 -0.700024)
			(stroke
				(width 0.1)
				(type default)
			)
			(layer "B.Fab")
		)
		(fp_line
			(start -0.899922 -0.700024)
			(end -0.899922 0.700024)
			(stroke
				(width 0.1)
				(type default)
			)
			(layer "B.Fab")
		)
		(fp_line
			(start 0.899922 -0.700024)
			(end -0.899922 -0.700024)
			(stroke
				(width 0.1)
				(type default)
			)
			(layer "B.Fab")
		)
		(fp_text user "+"
			(at 3.123946 0.762 180)
			(unlocked yes)
			(layer "B.SilkS")
			(effects
				(font
					(size 1.905 1.4224)
					(thickness 0.1524)
				)
				(justify left mirror)
			)
		)
		(fp_text user "-"
			(at -1.345438 -1.784604 90)
			(unlocked yes)
			(layer "B.SilkS")
			(effects
				(font
					(size 1.905 1.4224)
					(thickness 0.1524)
				)
				(justify left mirror)
			)
		)
		(fp_text user "+"
			(at 3.123946 0.762 180)
			(unlocked yes)
			(layer "B.Fab")
			(effects
				(font
					(size 1.905 1.4224)
					(thickness 0.1524)
				)
				(justify left mirror)
			)
		)
		(fp_text user "-"
			(at -3.880104 0.23495 90)
			(unlocked yes)
			(layer "B.Fab")
			(effects
				(font
					(size 1.905 1.4224)
					(thickness 0.1524)
				)
				(justify left mirror)
			)
		)
		(pad "1" smd rect
			(at 1.199896 0 180)
			(size 0.6604 1.3716)
			(layers "B.Cu" "B.Mask" "B.Paste")
			(net "PWRGD_FAIL_CPU0_CD_R1")
		)
		(pad "2" smd rect
			(at -1.199896 0)
			(size 0.6604 1.3716)
			(layers "B.Cu" "B.Mask" "B.Paste")
			(net "P3V3_AUX")
		)
	)
	(footprint ""
		(layer "B.Cu")
		(at 315.53404 -193.53911 -90)
		(property "Reference" "R94"
			(at 0 0 90)
			(layer "B.SilkS")
			(hide yes)
			(effects
				(font
					(size 1.27 1.27)
				)
				(justify mirror)
			)
		)
		(property "Value" ""
			(at 0 0 90)
			(layer "B.Fab")
			(effects
				(font
					(size 1.27 1.27)
				)
				(justify mirror)
			)
		)
		(duplicate_pad_numbers_are_jumpers no)
		(fp_line
			(start -0.7874 0.4064)
			(end 0.7874 0.4064)
			(stroke
				(width 0.1524)
				(type default)
			)
			(layer "B.SilkS")
		)
		(fp_line
			(start 0.7874 0.4064)
			(end 0.7874 -0.4064)
			(stroke
				(width 0.1524)
				(type default)
			)
			(layer "B.SilkS")
		)
		(fp_line
			(start -0.7874 -0.4064)
			(end -0.7874 0.4064)
			(stroke
				(width 0.1524)
				(type default)
			)
			(layer "B.SilkS")
		)
		(fp_line
			(start 0.7874 -0.4064)
			(end -0.7874 -0.4064)
			(stroke
				(width 0.1524)
				(type default)
			)
			(layer "B.SilkS")
		)
		(fp_line
			(start -0.67945 0.3048)
			(end -0.120396 0.3048)
			(stroke
				(width 0.1)
				(type default)
			)
			(layer "B.Fab")
		)
		(fp_line
			(start -0.120396 0.3048)
			(end -0.120396 0.2794)
			(stroke
				(width 0.1)
				(type default)
			)
			(layer "B.Fab")
		)
		(fp_line
			(start 0.12065 0.3048)
			(end 0.67945 0.3048)
			(stroke
				(width 0.1)
				(type default)
			)
			(layer "B.Fab")
		)
		(fp_line
			(start 0.67945 0.3048)
			(end 0.67945 -0.305054)
			(stroke
				(width 0.1)
				(type default)
			)
			(layer "B.Fab")
		)
		(fp_line
			(start -0.120396 0.2794)
			(end 0.12065 0.2794)
			(stroke
				(width 0.1)
				(type default)
			)
			(layer "B.Fab")
		)
		(fp_line
			(start 0.12065 0.2794)
			(end 0.12065 0.3048)
			(stroke
				(width 0.1)
				(type default)
			)
			(layer "B.Fab")
		)
		(fp_line
			(start -0.12065 -0.2794)
			(end -0.12065 -0.3048)
			(stroke
				(width 0.1)
				(type default)
			)
			(layer "B.Fab")
		)
		(fp_line
			(start 0.12065 -0.2794)
			(end -0.12065 -0.2794)
			(stroke
				(width 0.1)
				(type default)
			)
			(layer "B.Fab")
		)
		(fp_line
			(start -0.67945 -0.3048)
			(end -0.67945 0.3048)
			(stroke
				(width 0.1)
				(type default)
			)
			(layer "B.Fab")
		)
		(fp_line
			(start -0.12065 -0.3048)
			(end -0.67945 -0.3048)
			(stroke
				(width 0.1)
				(type default)
			)
			(layer "B.Fab")
		)
		(fp_line
			(start 0.12065 -0.305054)
			(end 0.12065 -0.2794)
			(stroke
				(width 0.1)
				(type default)
			)
			(layer "B.Fab")
		)
		(fp_line
			(start 0.67945 -0.305054)
			(end 0.12065 -0.305054)
			(stroke
				(width 0.1)
				(type default)
			)
			(layer "B.Fab")
		)
		(pad "1" smd circle
			(at 0.40005 0 90)
			(size 0 0)
			(layers "B.Cu" "B.Mask" "B.Paste")
			(net "PVNN_TERM_CPU0")
		)
		(pad "2" smd circle
			(at -0.40005 0 90)
			(size 0 0)
			(layers "B.Cu" "B.Mask" "B.Paste")
			(net "PU_CPU0_UPI0_AC_COUPLING")
		)
	)
	(footprint ""
		(layer "B.Cu")
		(at 330.577698 -190.82893 -90)
		(property "Reference" "R184"
			(at 0 0 90)
			(layer "B.SilkS")
			(hide yes)
			(effects
				(font
					(size 1.27 1.27)
				)
				(justify mirror)
			)
		)
		(property "Value" ""
			(at 0 0 90)
			(layer "B.Fab")
			(effects
				(font
					(size 1.27 1.27)
				)
				(justify mirror)
			)
		)
		(duplicate_pad_numbers_are_jumpers no)
		(fp_line
			(start -0.7874 0.4064)
			(end 0.7874 0.4064)
			(stroke
				(width 0.1524)
				(type default)
			)
			(layer "B.SilkS")
		)
		(fp_line
			(start 0.7874 0.4064)
			(end 0.7874 -0.4064)
			(stroke
				(width 0.1524)
				(type default)
			)
			(layer "B.SilkS")
		)
		(fp_line
			(start -0.7874 -0.4064)
			(end -0.7874 0.4064)
			(stroke
				(width 0.1524)
				(type default)
			)
			(layer "B.SilkS")
		)
		(fp_line
			(start 0.7874 -0.4064)
			(end -0.7874 -0.4064)
			(stroke
				(width 0.1524)
				(type default)
			)
			(layer "B.SilkS")
		)
		(fp_line
			(start -0.67945 0.3048)
			(end -0.120396 0.3048)
			(stroke
				(width 0.1)
				(type default)
			)
			(layer "B.Fab")
		)
		(fp_line
			(start -0.120396 0.3048)
			(end -0.120396 0.2794)
			(stroke
				(width 0.1)
				(type default)
			)
			(layer "B.Fab")
		)
		(fp_line
			(start 0.12065 0.3048)
			(end 0.67945 0.3048)
			(stroke
				(width 0.1)
				(type default)
			)
			(layer "B.Fab")
		)
		(fp_line
			(start 0.67945 0.3048)
			(end 0.67945 -0.305054)
			(stroke
				(width 0.1)
				(type default)
			)
			(layer "B.Fab")
		)
		(fp_line
			(start -0.120396 0.2794)
			(end 0.12065 0.2794)
			(stroke
				(width 0.1)
				(type default)
			)
			(layer "B.Fab")
		)
		(fp_line
			(start 0.12065 0.2794)
			(end 0.12065 0.3048)
			(stroke
				(width 0.1)
				(type default)
			)
			(layer "B.Fab")
		)
		(fp_line
			(start -0.12065 -0.2794)
			(end -0.12065 -0.3048)
			(stroke
				(width 0.1)
				(type default)
			)
			(layer "B.Fab")
		)
		(fp_line
			(start 0.12065 -0.2794)
			(end -0.12065 -0.2794)
			(stroke
				(width 0.1)
				(type default)
			)
			(layer "B.Fab")
		)
		(fp_line
			(start -0.67945 -0.3048)
			(end -0.67945 0.3048)
			(stroke
				(width 0.1)
				(type default)
			)
			(layer "B.Fab")
		)
		(fp_line
			(start -0.12065 -0.3048)
			(end -0.67945 -0.3048)
			(stroke
				(width 0.1)
				(type default)
			)
			(layer "B.Fab")
		)
		(fp_line
			(start 0.12065 -0.305054)
			(end 0.12065 -0.2794)
			(stroke
				(width 0.1)
				(type default)
			)
			(layer "B.Fab")
		)
		(fp_line
			(start 0.67945 -0.305054)
			(end 0.12065 -0.305054)
			(stroke
				(width 0.1)
				(type default)
			)
			(layer "B.Fab")
		)
		(pad "1" smd circle
			(at 0.40005 0 90)
			(size 0 0)
			(layers "B.Cu" "B.Mask" "B.Paste")
			(net "PWRGD_CPU0_BUF_R")
		)
		(pad "2" smd circle
			(at -0.40005 0 90)
			(size 0 0)
			(layers "B.Cu" "B.Mask" "B.Paste")
			(net "PWRGD_CPU0_LVC1")
		)
	)
	(footprint ""
		(layer "B.Cu")
		(at 315.110622 -52.187348)
		(property "Reference" "R4107"
			(at 0 0 0)
			(layer "B.SilkS")
			(hide yes)
			(effects
				(font
					(size 1.27 1.27)
				)
				(justify mirror)
			)
		)
		(property "Value" ""
			(at 0 0 0)
			(layer "B.Fab")
			(effects
				(font
					(size 1.27 1.27)
				)
				(justify mirror)
			)
		)
		(duplicate_pad_numbers_are_jumpers no)
		(fp_line
			(start -0.7874 -0.4064)
			(end -0.7874 0.4064)
			(stroke
				(width 0.1524)
				(type default)
			)
			(layer "B.SilkS")
		)
		(fp_line
			(start -0.7874 0.4064)
			(end 0.7874 0.4064)
			(stroke
				(width 0.1524)
				(type default)
			)
			(layer "B.SilkS")
		)
		(fp_line
			(start 0.7874 -0.4064)
			(end -0.7874 -0.4064)
			(stroke
				(width 0.1524)
				(type default)
			)
			(layer "B.SilkS")
		)
		(fp_line
			(start 0.7874 0.4064)
			(end 0.7874 -0.4064)
			(stroke
				(width 0.1524)
				(type default)
			)
			(layer "B.SilkS")
		)
		(fp_line
			(start -0.67945 -0.3048)
			(end -0.67945 0.3048)
			(stroke
				(width 0.1)
				(type default)
			)
			(layer "B.Fab")
		)
		(fp_line
			(start -0.67945 0.3048)
			(end -0.120396 0.3048)
			(stroke
				(width 0.1)
				(type default)
			)
			(layer "B.Fab")
		)
		(fp_line
			(start -0.12065 -0.3048)
			(end -0.67945 -0.3048)
			(stroke
				(width 0.1)
				(type default)
			)
			(layer "B.Fab")
		)
		(fp_line
			(start -0.12065 -0.2794)
			(end -0.12065 -0.3048)
			(stroke
				(width 0.1)
				(type default)
			)
			(layer "B.Fab")
		)
		(fp_line
			(start -0.120396 0.2794)
			(end 0.12065 0.2794)
			(stroke
				(width 0.1)
				(type default)
			)
			(layer "B.Fab")
		)
		(fp_line
			(start -0.120396 0.3048)
			(end -0.120396 0.2794)
			(stroke
				(width 0.1)
				(type default)
			)
			(layer "B.Fab")
		)
		(fp_line
			(start 0.12065 -0.305054)
			(end 0.12065 -0.2794)
			(stroke
				(width 0.1)
				(type default)
			)
			(layer "B.Fab")
		)
		(fp_line
			(start 0.12065 -0.2794)
			(end -0.12065 -0.2794)
			(stroke
				(width 0.1)
				(type default)
			)
			(layer "B.Fab")
		)
		(fp_line
			(start 0.12065 0.2794)
			(end 0.12065 0.3048)
			(stroke
				(width 0.1)
				(type default)
			)
			(layer "B.Fab")
		)
		(fp_line
			(start 0.12065 0.3048)
			(end 0.67945 0.3048)
			(stroke
				(width 0.1)
				(type default)
			)
			(layer "B.Fab")
		)
		(fp_line
			(start 0.67945 -0.305054)
			(end 0.12065 -0.305054)
			(stroke
				(width 0.1)
				(type default)
			)
			(layer "B.Fab")
		)
		(fp_line
			(start 0.67945 0.3048)
			(end 0.67945 -0.305054)
			(stroke
				(width 0.1)
				(type default)
			)
			(layer "B.Fab")
		)
		(pad "1" smd circle
			(at 0.40005 0 180)
			(size 0 0)
			(layers "B.Cu" "B.Mask" "B.Paste")
			(net "PD_GPP_I_17")
		)
		(pad "2" smd circle
			(at -0.40005 0 180)
			(size 0 0)
			(layers "B.Cu" "B.Mask" "B.Paste")
			(net "GND")
		)
	)
)
